(kicad_pcb
	(version 20221018)
	(generator pcbnew)
	(general
    (thickness 1.518)
  )
	(paper "A4")
	(title_block
    (title "Kria K26 Devboard")
    (date "2024-03-26")
    (rev "1.2.5")
    (comment 1 "www.antmicro.com")
    (comment 2 "Antmicro Ltd.")
		(comment 9 "footprints 15-15 of 660")
	)
	(layers
    (0 "F.Cu" mixed)
    (1 "In1.Cu" power)
    (2 "In2.Cu" mixed)
    (3 "In3.Cu" power)
    (4 "In4.Cu" mixed)
    (5 "In5.Cu" power)
    (6 "In6.Cu" mixed)
    (31 "B.Cu" power)
    (32 "B.Adhes" user "B.Adhesive")
    (33 "F.Adhes" user "F.Adhesive")
    (34 "B.Paste" user)
    (35 "F.Paste" user)
    (36 "B.SilkS" user "B.Silkscreen")
    (37 "F.SilkS" user "F.Silkscreen")
    (38 "B.Mask" user)
    (39 "F.Mask" user)
    (40 "Dwgs.User" user "User.Drawings")
    (41 "Cmts.User" user "User.Comments")
    (42 "Eco1.User" user "User.Eco1")
    (43 "Eco2.User" user "User.Eco2")
    (44 "Edge.Cuts" user)
    (45 "Margin" user)
    (46 "B.CrtYd" user "B.Courtyard")
    (47 "F.CrtYd" user "F.Courtyard")
    (48 "B.Fab" user)
    (49 "F.Fab" user)
  )
	(footprint "kria-k26-devboard-footprints:Conn_JST_SH_1x8_BM08B-SRSS-TB-LF-SN" (layer "F.Cu")
    (at 111.785 149.698 180)
    (descr "Connector SMD pitch 1mm")
    (tags "connector SMD pitch 1mm")
    (property "Author" "Antmicro")
    (property "License" "Apache-2.0")
    (property "MPN" "BM08B-SRSS-TB(LF)(SN)")
    (property "Manufacturer" "JST Automotive Connectors")
    (property "Sheetfile" "reset.kicad_sch")
    (property "Sheetname" "Reset logic")
    (property "ki_description" "Pin Header, Wire-to-Board, 1 mm, 1 Rows, 8 Contacts, Surface Mount, SR")
    (property "ki_keywords" "VERTICAL, SMT, WIRE-BOARD, CONNECTOR")
    (attr smd)
    (fp_text reference "J7" (at -6.525 0.388) (layer "F.SilkS")
        (effects (font (size 0.7 0.7) (thickness 0.15)) (justify right bottom))
    )
    (fp_text value "JST_SH_1x8_BM08B-SRSS-TB-LF-SN" (at 0 2.7) (layer "F.Fab") hide
        (effects (font (size 0.7 0.7) (thickness 0.15)) (justify right bottom))
    )
    (fp_text user "License: Apache-2.0" (at -5.49 6.949) (layer "F.Fab") hide
        (effects (font (size 0.7 0.7) (thickness 0.15)) (justify right bottom))
    )
    (fp_text user "Author: Antmicro" (at -5.49 5.949) (layer "F.Fab") hide
        (effects (font (size 0.7 0.7) (thickness 0.15)) (justify right bottom))
    )
    (fp_text user "${REFERENCE}" (at -5.49 4.949) (layer "F.Fab") hide
        (effects (font (size 0.7 0.7) (thickness 0.15)) (justify right bottom))
    )
    (fp_line (start -5 0.973) (end -5 0)
      (stroke (width 0.15) (type solid)) (layer "F.SilkS"))
    (fp_line (start -4.242 0.973) (end -5 0.973)
      (stroke (width 0.15) (type solid)) (layer "F.SilkS"))
    (fp_line (start 3.88 -1.926) (end -3.88 -1.926)
      (stroke (width 0.15) (type solid)) (layer "F.SilkS"))
    (fp_line (start 4.242 0.973) (end 5 0.973)
      (stroke (width 0.15) (type solid)) (layer "F.SilkS"))
    (fp_line (start 5 0.973) (end 5 0)
      (stroke (width 0.15) (type solid)) (layer "F.SilkS"))
    (fp_circle (center -3.5 2.573) (end -3.45 2.573)
      (stroke (width 0.15) (type solid)) (fill solid) (layer "F.SilkS"))
    (fp_line (start -5.49 -2.337) (end 5.5 -2.337)
      (stroke (width 0.05) (type solid)) (layer "F.CrtYd"))
    (fp_line (start -5.49 -0.037) (end -5.49 -2.337)
      (stroke (width 0.05) (type solid)) (layer "F.CrtYd"))
    (fp_line (start -5.28 -0.037) (end -5.49 -0.037)
      (stroke (width 0.05) (type solid)) (layer "F.CrtYd"))
    (fp_line (start -5.28 1.263) (end -5.28 -0.037)
      (stroke (width 0.05) (type solid)) (layer "F.CrtYd"))
    (fp_line (start -4.04 1.263) (end -5.28 1.263)
      (stroke (width 0.05) (type solid)) (layer "F.CrtYd"))
    (fp_line (start -4.04 2.173) (end -4.04 1.263)
      (stroke (width 0.05) (type solid)) (layer "F.CrtYd"))
    (fp_line (start 4.05 1.263) (end 4.05 2.173)
      (stroke (width 0.05) (type solid)) (layer "F.CrtYd"))
    (fp_line (start 4.05 2.173) (end -4.04 2.173)
      (stroke (width 0.05) (type solid)) (layer "F.CrtYd"))
    (fp_line (start 5.25 -0.037) (end 5.25 1.263)
      (stroke (width 0.05) (type solid)) (layer "F.CrtYd"))
    (fp_line (start 5.25 1.263) (end 4.05 1.263)
      (stroke (width 0.05) (type solid)) (layer "F.CrtYd"))
    (fp_line (start 5.5 -2.337) (end 5.5 -0.037)
      (stroke (width 0.05) (type solid)) (layer "F.CrtYd"))
    (fp_line (start 5.5 -0.037) (end 5.25 -0.037)
      (stroke (width 0.05) (type solid)) (layer "F.CrtYd"))
    (fp_line (start -5 0.573) (end -4.6 0.973)
      (stroke (width 0.15) (type solid)) (layer "F.Fab"))
    (fp_rect (start -5 -1.927) (end 5 0.973)
      (stroke (width 0.15) (type solid)) (fill none) (layer "F.Fab"))
    (pad "1" smd rect (at -3.5 1.298) (size 0.6 1.55) (layers "F.Cu" "F.Paste" "F.Mask")
      (net 1 "GND") (pinfunction "Pin_1") (pintype "passive"))
    (pad "2" smd rect (at -2.5 1.298) (size 0.6 1.55) (layers "F.Cu" "F.Paste" "F.Mask")
      (net 221 "/PCIE M2 key E /~{M2_PERST}") (pinfunction "Pin_2") (pintype "passive"))
    (pad "3" smd rect (at -1.5 1.298) (size 0.6 1.55) (layers "F.Cu" "F.Paste" "F.Mask")
      (net 198 "/Camera interface/CAM0_RST") (pinfunction "Pin_3") (pintype "passive"))
    (pad "4" smd rect (at -0.5 1.298) (size 0.6 1.55) (layers "F.Cu" "F.Paste" "F.Mask")
      (net 176 "/Ethernet/~{ETH_RESET}") (pinfunction "Pin_4") (pintype "passive"))
    (pad "5" smd rect (at 0.5 1.298) (size 0.6 1.55) (layers "F.Cu" "F.Paste" "F.Mask")
      (net 175 "/Reset logic/~{USB_HUB_RESET}") (pinfunction "Pin_5") (pintype "passive"))
    (pad "6" smd rect (at 1.5 1.298) (size 0.6 1.55) (layers "F.Cu" "F.Paste" "F.Mask")
      (net 178 "/Reset logic/~{USB_PHY_RESET}") (pinfunction "Pin_6") (pintype "passive"))
    (pad "7" smd rect (at 2.5 1.298) (size 0.6 1.55) (layers "F.Cu" "F.Paste" "F.Mask")
      (net 177 "/Reset logic/~{SD_CARD_RESET}") (pinfunction "Pin_7") (pintype "passive"))
    (pad "8" smd rect (at 3.5 1.298) (size 0.6 1.55) (layers "F.Cu" "F.Paste" "F.Mask")
      (net 151 "/Debug and JTAG/~{PS_POR}") (pinfunction "Pin_8") (pintype "passive"))
    (pad "MP" smd rect (at -4.798 -1.225) (size 1.2 1.8) (layers "F.Cu" "F.Paste" "F.Mask")
      (net 799 "unconnected-(J7-PadMP)") (pinfunction "MP") (pintype "passive+no_connect"))
    (pad "MP" smd rect (at 4.801 -1.225) (size 1.2 1.8) (layers "F.Cu" "F.Paste" "F.Mask")
      (net 799 "unconnected-(J7-PadMP)") (pinfunction "MP") (pintype "passive+no_connect"))
  )
)
